(kicad_pcb
	(version 20260206)
	(generator "pcbnew")
	(generator_version "10.0")
	(general
		(thickness 1.6)
		(legacy_teardrops no)
	)
	(paper "A4")
	(title_block
		(title "dpb — 14545-sa.0730WZS0815.brd")
		(comment 1 "Honey Badger (Wiwynn) / footprints 643-649 of 1066")
	)
	(layers
		(0 "F.Cu" signal "TOP")
		(4 "In1.Cu" signal "L2GND")
		(6 "In2.Cu" signal "L3")
		(8 "In3.Cu" signal "L4VCC")
		(10 "In4.Cu" signal "L5VCC")
		(12 "In5.Cu" signal "L6")
		(14 "In6.Cu" signal "L7GND")
		(2 "B.Cu" signal "BOTTOM")
		(9 "F.Adhes" user "F.Adhesive")
		(11 "B.Adhes" user "B.Adhesive")
		(13 "F.Paste" user "Package Geometry/Pastemask Top")
		(15 "B.Paste" user "Package Geometry/Pastemask Bottom")
		(5 "F.SilkS" user "Ref Des/Silkscreen Top")
		(7 "B.SilkS" user "Ref Des/Silkscreen Bottom")
		(1 "F.Mask" user "Board Geometry/Soldermask Top")
		(3 "B.Mask" user "Board Geometry/Soldermask Bottom")
		(17 "Dwgs.User" user "User.Drawings")
		(19 "Cmts.User" user "User.Comments")
		(21 "Eco1.User" user "User.Eco1")
		(23 "Eco2.User" user "User.Eco2")
		(25 "Edge.Cuts" user "Board Geometry/Outline")
		(27 "Margin" user)
		(31 "F.CrtYd" user "Package Geometry/Place Bound Top")
		(29 "B.CrtYd" user "Package Geometry/Place Bound Bottom")
		(35 "F.Fab" user "Ref Des/Assembly Top")
		(33 "B.Fab" user "Ref Des/Assembly Bottom")
	)
	(footprint ""
		(layer "F.Cu")
		(at 32.86506 -373.187214 -90)
		(property "Reference" "C201"
			(at 0 0 270)
			(layer "F.SilkS")
			(hide yes)
			(effects
				(font
					(size 1.27 1.27)
				)
			)
		)
		(property "Value" "SCD01U50V2KX-1GP"
			(at 1.1811 -2.7051 270)
			(unlocked yes)
			(layer "F.Fab")
			(hide yes)
			(effects
				(font
					(size 1.016 1.016)
					(thickness 0.1524)
				)
			)
		)
		(property "Device Type" "C402H22"
			(at 1.1811 -4.2291 270)
			(unlocked yes)
			(layer "F.Fab")
			(hide yes)
			(effects
				(font
					(size 1.016 1.016)
					(thickness 0.1524)
				)
			)
		)
		(duplicate_pad_numbers_are_jumpers no)
		(fp_rect
			(start -0.4318 0.9525)
			(end 0.4318 -0.9525)
			(stroke
				(width 0)
				(type default)
			)
			(fill no)
			(layer "F.CrtYd")
		)
		(fp_rect
			(start -0.4318 0.9525)
			(end 0.4318 -0.9525)
			(stroke
				(width 0)
				(type default)
			)
			(fill no)
			(layer "F.Fab")
		)
		(pad "1" smd custom
			(at 0 -0.4445 270)
			(size 0.1524 0.1524)
			(layers "F.Cu" "F.Mask" "F.Paste")
			(net "SAS2X28_DRIVE_RX_P_B6")
			(options
				(clearance outline)
				(anchor circle)
			)
			(primitives
				(gr_poly
					(pts
						(arc
							(start 0.3048 -0.2032)
							(mid 0.275042 -0.275042)
							(end 0.2032 -0.3048)
						)
						(arc
							(start -0.2032 -0.3048)
							(mid -0.275042 -0.275042)
							(end -0.3048 -0.2032)
						)
						(arc
							(start -0.3048 0.2032)
							(mid -0.275042 0.275042)
							(end -0.2032 0.3048)
						)
						(arc
							(start 0.2032 0.3048)
							(mid 0.275042 0.275042)
							(end 0.3048 0.2032)
						)
					)
					(width 0)
					(fill yes)
				)
			)
		)
		(pad "2" smd custom
			(at 0 0.4445 270)
			(size 0.1524 0.1524)
			(layers "F.Cu" "F.Mask" "F.Paste")
			(net "SAS2X28_B_HDD6_RX_+")
			(options
				(clearance outline)
				(anchor circle)
			)
			(primitives
				(gr_poly
					(pts
						(arc
							(start 0.3048 -0.2032)
							(mid 0.275042 -0.275042)
							(end 0.2032 -0.3048)
						)
						(arc
							(start -0.2032 -0.3048)
							(mid -0.275042 -0.275042)
							(end -0.3048 -0.2032)
						)
						(arc
							(start -0.3048 0.2032)
							(mid -0.275042 0.275042)
							(end -0.2032 0.3048)
						)
						(arc
							(start 0.2032 0.3048)
							(mid 0.275042 0.275042)
							(end 0.3048 0.2032)
						)
					)
					(width 0)
					(fill yes)
				)
			)
		)
	)
	(footprint ""
		(layer "F.Cu")
		(at 64.3128 -390.5758)
		(property "Reference" "C211"
			(at 0 0 0)
			(layer "F.SilkS")
			(hide yes)
			(effects
				(font
					(size 1.27 1.27)
				)
			)
		)
		(property "Value" "SC1U25V3KX-1-GP"
			(at 0 -2.8194 0)
			(unlocked yes)
			(layer "F.Fab")
			(hide yes)
			(effects
				(font
					(size 1.016 1.016)
					(thickness 0.1524)
				)
			)
		)
		(property "Device Type" "C603H36"
			(at 0 -4.3434 0)
			(unlocked yes)
			(layer "F.Fab")
			(hide yes)
			(effects
				(font
					(size 1.016 1.016)
					(thickness 0.1524)
				)
			)
		)
		(duplicate_pad_numbers_are_jumpers no)
		(fp_line
			(start 0.508 0)
			(end -0.508 0)
			(stroke
				(width 0.2032)
				(type default)
			)
			(layer "F.SilkS")
		)
		(fp_rect
			(start -0.5842 1.3335)
			(end 0.5842 -1.3335)
			(stroke
				(width 0)
				(type default)
			)
			(fill no)
			(layer "F.CrtYd")
		)
		(fp_rect
			(start -0.5842 1.3335)
			(end 0.5842 -1.3335)
			(stroke
				(width 0)
				(type default)
			)
			(fill no)
			(layer "F.Fab")
		)
		(pad "1" smd custom
			(at 0 -0.762)
			(size 0.2159 0.2159)
			(layers "F.Cu" "F.Mask" "F.Paste")
			(net "P12V_HDD6")
			(options
				(clearance outline)
				(anchor circle)
			)
			(primitives
				(gr_poly
					(pts
						(arc
							(start -0.3302 -0.4318)
							(mid -0.402042 -0.402042)
							(end -0.4318 -0.3302)
						)
						(arc
							(start -0.4318 0.3302)
							(mid -0.402042 0.402042)
							(end -0.3302 0.4318)
						)
						(arc
							(start 0.3302 0.4318)
							(mid 0.402042 0.402042)
							(end 0.4318 0.3302)
						)
						(arc
							(start 0.4318 -0.3302)
							(mid 0.402042 -0.402042)
							(end 0.3302 -0.4318)
						)
					)
					(width 0)
					(fill yes)
				)
			)
		)
		(pad "2" smd custom
			(at 0 0.762)
			(size 0.2159 0.2159)
			(layers "F.Cu" "F.Mask" "F.Paste")
			(net "GND")
			(options
				(clearance outline)
				(anchor circle)
			)
			(primitives
				(gr_poly
					(pts
						(arc
							(start -0.3302 -0.4318)
							(mid -0.402042 -0.402042)
							(end -0.4318 -0.3302)
						)
						(arc
							(start -0.4318 0.3302)
							(mid -0.402042 0.402042)
							(end -0.3302 0.4318)
						)
						(arc
							(start 0.3302 0.4318)
							(mid 0.402042 0.402042)
							(end 0.4318 0.3302)
						)
						(arc
							(start 0.4318 -0.3302)
							(mid 0.402042 -0.402042)
							(end 0.3302 -0.4318)
						)
					)
					(width 0)
					(fill yes)
				)
			)
		)
	)
	(footprint ""
		(layer "F.Cu")
		(at 207.009746 -452.6407 180)
		(property "Reference" "R328"
			(at 0 0 180)
			(layer "F.SilkS")
			(hide yes)
			(effects
				(font
					(size 1.27 1.27)
				)
			)
		)
		(property "Value" "4K7R2J-2-GP"
			(at 0.064008 -3.993896 180)
			(unlocked yes)
			(layer "F.Fab")
			(hide yes)
			(effects
				(font
					(size 1.016 1.016)
					(thickness 0.1524)
				)
			)
		)
		(property "Device Type" "R402H16"
			(at 0.064008 -5.517896 180)
			(unlocked yes)
			(layer "F.Fab")
			(hide yes)
			(effects
				(font
					(size 1.016 1.016)
					(thickness 0.1524)
				)
			)
		)
		(duplicate_pad_numbers_are_jumpers no)
		(fp_line
			(start 0.508 -0.9398)
			(end -0.508 -0.9398)
			(stroke
				(width 0.1524)
				(type default)
			)
			(layer "F.SilkS")
		)
		(fp_line
			(start -0.508 -0.9398)
			(end -0.508 0.9398)
			(stroke
				(width 0.1524)
				(type default)
			)
			(layer "F.SilkS")
		)
		(fp_rect
			(start -0.508 0.9398)
			(end 0.508 -0.9398)
			(stroke
				(width 0)
				(type default)
			)
			(fill no)
			(layer "F.CrtYd")
		)
		(fp_rect
			(start -0.508 0.9398)
			(end 0.508 -0.9398)
			(stroke
				(width 0)
				(type default)
			)
			(fill no)
			(layer "F.Fab")
		)
		(pad "1" smd custom
			(at 0 -0.4445 180)
			(size 0.1397 0.1397)
			(layers "F.Cu" "F.Mask" "F.Paste")
			(net "P3V3")
			(options
				(clearance outline)
				(anchor circle)
			)
			(primitives
				(gr_poly
					(pts
						(arc
							(start -0.1778 -0.2794)
							(mid -0.249642 -0.249642)
							(end -0.2794 -0.1778)
						)
						(arc
							(start -0.2794 0.1778)
							(mid -0.249642 0.249642)
							(end -0.1778 0.2794)
						)
						(arc
							(start 0.1778 0.2794)
							(mid 0.249642 0.249642)
							(end 0.2794 0.1778)
						)
						(arc
							(start 0.2794 -0.1778)
							(mid 0.249642 -0.249642)
							(end 0.1778 -0.2794)
						)
					)
					(width 0)
					(fill yes)
				)
			)
		)
		(pad "2" smd custom
			(at 0 0.4445 180)
			(size 0.1397 0.1397)
			(layers "F.Cu" "F.Mask" "F.Paste")
			(net "I2C_B_TMP3_A2")
			(options
				(clearance outline)
				(anchor circle)
			)
			(primitives
				(gr_poly
					(pts
						(arc
							(start -0.1778 -0.2794)
							(mid -0.249642 -0.249642)
							(end -0.2794 -0.1778)
						)
						(arc
							(start -0.2794 0.1778)
							(mid -0.249642 0.249642)
							(end -0.1778 0.2794)
						)
						(arc
							(start 0.1778 0.2794)
							(mid 0.249642 0.249642)
							(end 0.2794 0.1778)
						)
						(arc
							(start 0.2794 -0.1778)
							(mid 0.249642 -0.249642)
							(end 0.1778 -0.2794)
						)
					)
					(width 0)
					(fill yes)
				)
			)
		)
	)
	(footprint ""
		(layer "F.Cu")
		(at 79.304134 -495.022886 -90)
		(property "Reference" "R183"
			(at 0 0 270)
			(layer "F.SilkS")
			(hide yes)
			(effects
				(font
					(size 1.27 1.27)
				)
			)
		)
		(property "Value" "0R2J-2-GP"
			(at 0.064008 -3.993896 270)
			(unlocked yes)
			(layer "F.Fab")
			(hide yes)
			(effects
				(font
					(size 1.016 1.016)
					(thickness 0.1524)
				)
			)
		)
		(property "Device Type" "R402H16"
			(at 0.064008 -5.517896 270)
			(unlocked yes)
			(layer "F.Fab")
			(hide yes)
			(effects
				(font
					(size 1.016 1.016)
					(thickness 0.1524)
				)
			)
		)
		(duplicate_pad_numbers_are_jumpers no)
		(fp_line
			(start -0.508 -0.9398)
			(end -0.508 0.9398)
			(stroke
				(width 0.1524)
				(type default)
			)
			(layer "F.SilkS")
		)
		(fp_line
			(start 0.508 -0.9398)
			(end -0.508 -0.9398)
			(stroke
				(width 0.1524)
				(type default)
			)
			(layer "F.SilkS")
		)
		(fp_rect
			(start -0.508 0.9398)
			(end 0.508 -0.9398)
			(stroke
				(width 0)
				(type default)
			)
			(fill no)
			(layer "F.CrtYd")
		)
		(fp_rect
			(start -0.508 0.9398)
			(end 0.508 -0.9398)
			(stroke
				(width 0)
				(type default)
			)
			(fill no)
			(layer "F.Fab")
		)
		(pad "1" smd custom
			(at 0 -0.4445 270)
			(size 0.1397 0.1397)
			(layers "F.Cu" "F.Mask" "F.Paste")
			(net "DRIVE_PWR5")
			(options
				(clearance outline)
				(anchor circle)
			)
			(primitives
				(gr_poly
					(pts
						(arc
							(start -0.1778 -0.2794)
							(mid -0.249642 -0.249642)
							(end -0.2794 -0.1778)
						)
						(arc
							(start -0.2794 0.1778)
							(mid -0.249642 0.249642)
							(end -0.1778 0.2794)
						)
						(arc
							(start 0.1778 0.2794)
							(mid 0.249642 0.249642)
							(end 0.2794 0.1778)
						)
						(arc
							(start 0.2794 -0.1778)
							(mid 0.249642 -0.249642)
							(end 0.1778 -0.2794)
						)
					)
					(width 0)
					(fill yes)
				)
			)
		)
		(pad "2" smd custom
			(at 0 0.4445 270)
			(size 0.1397 0.1397)
			(layers "F.Cu" "F.Mask" "F.Paste")
			(net "SW_PWR_HDD5")
			(options
				(clearance outline)
				(anchor circle)
			)
			(primitives
				(gr_poly
					(pts
						(arc
							(start -0.1778 -0.2794)
							(mid -0.249642 -0.249642)
							(end -0.2794 -0.1778)
						)
						(arc
							(start -0.2794 0.1778)
							(mid -0.249642 0.249642)
							(end -0.1778 0.2794)
						)
						(arc
							(start 0.1778 0.2794)
							(mid 0.249642 0.249642)
							(end 0.2794 0.1778)
						)
						(arc
							(start 0.2794 -0.1778)
							(mid 0.249642 -0.249642)
							(end 0.1778 -0.2794)
						)
					)
					(width 0)
					(fill yes)
				)
			)
		)
	)
	(footprint ""
		(layer "F.Cu")
		(at 197.103746 -185.0517 -90)
		(property "Reference" "R436"
			(at 0 0 270)
			(layer "F.SilkS")
			(hide yes)
			(effects
				(font
					(size 1.27 1.27)
				)
			)
		)
		(property "Value" "4K7R2J-2-GP"
			(at 0.064008 -3.993896 270)
			(unlocked yes)
			(layer "F.Fab")
			(hide yes)
			(effects
				(font
					(size 1.016 1.016)
					(thickness 0.1524)
				)
			)
		)
		(property "Device Type" "R402H16"
			(at 0.064008 -5.517896 270)
			(unlocked yes)
			(layer "F.Fab")
			(hide yes)
			(effects
				(font
					(size 1.016 1.016)
					(thickness 0.1524)
				)
			)
		)
		(duplicate_pad_numbers_are_jumpers no)
		(fp_line
			(start -0.508 -0.9398)
			(end -0.508 0.9398)
			(stroke
				(width 0.1524)
				(type default)
			)
			(layer "F.SilkS")
		)
		(fp_line
			(start 0.508 -0.9398)
			(end -0.508 -0.9398)
			(stroke
				(width 0.1524)
				(type default)
			)
			(layer "F.SilkS")
		)
		(fp_rect
			(start -0.508 0.9398)
			(end 0.508 -0.9398)
			(stroke
				(width 0)
				(type default)
			)
			(fill no)
			(layer "F.CrtYd")
		)
		(fp_rect
			(start -0.508 0.9398)
			(end 0.508 -0.9398)
			(stroke
				(width 0)
				(type default)
			)
			(fill no)
			(layer "F.Fab")
		)
		(pad "1" smd custom
			(at 0 -0.4445 270)
			(size 0.1397 0.1397)
			(layers "F.Cu" "F.Mask" "F.Paste")
			(net "P3V3")
			(options
				(clearance outline)
				(anchor circle)
			)
			(primitives
				(gr_poly
					(pts
						(arc
							(start -0.1778 -0.2794)
							(mid -0.249642 -0.249642)
							(end -0.2794 -0.1778)
						)
						(arc
							(start -0.2794 0.1778)
							(mid -0.249642 0.249642)
							(end -0.1778 0.2794)
						)
						(arc
							(start 0.1778 0.2794)
							(mid 0.249642 0.249642)
							(end 0.2794 0.1778)
						)
						(arc
							(start 0.2794 -0.1778)
							(mid 0.249642 -0.249642)
							(end 0.1778 -0.2794)
						)
					)
					(width 0)
					(fill yes)
				)
			)
		)
		(pad "2" smd custom
			(at 0 0.4445 270)
			(size 0.1397 0.1397)
			(layers "F.Cu" "F.Mask" "F.Paste")
			(net "SAS_EXP_A_PWR3")
			(options
				(clearance outline)
				(anchor circle)
			)
			(primitives
				(gr_poly
					(pts
						(arc
							(start -0.1778 -0.2794)
							(mid -0.249642 -0.249642)
							(end -0.2794 -0.1778)
						)
						(arc
							(start -0.2794 0.1778)
							(mid -0.249642 0.249642)
							(end -0.1778 0.2794)
						)
						(arc
							(start 0.1778 0.2794)
							(mid 0.249642 0.249642)
							(end 0.2794 0.1778)
						)
						(arc
							(start 0.2794 -0.1778)
							(mid 0.249642 -0.249642)
							(end 0.1778 -0.2794)
						)
					)
					(width 0)
					(fill yes)
				)
			)
		)
	)
	(footprint ""
		(layer "F.Cu")
		(at 217.254582 -283.182568 180)
		(property "Reference" "C138"
			(at 0 0 180)
			(layer "F.SilkS")
			(hide yes)
			(effects
				(font
					(size 1.27 1.27)
				)
			)
		)
		(property "Value" "SC1U16V3KX-5GP"
			(at 0 -2.8194 180)
			(unlocked yes)
			(layer "F.Fab")
			(hide yes)
			(effects
				(font
					(size 1.016 1.016)
					(thickness 0.1524)
				)
			)
		)
		(property "Device Type" "C603H36"
			(at 0 -4.3434 180)
			(unlocked yes)
			(layer "F.Fab")
			(hide yes)
			(effects
				(font
					(size 1.016 1.016)
					(thickness 0.1524)
				)
			)
		)
		(duplicate_pad_numbers_are_jumpers no)
		(fp_line
			(start 0.508 0)
			(end -0.508 0)
			(stroke
				(width 0.2032)
				(type default)
			)
			(layer "F.SilkS")
		)
		(fp_rect
			(start -0.5842 1.3335)
			(end 0.5842 -1.3335)
			(stroke
				(width 0)
				(type default)
			)
			(fill no)
			(layer "F.CrtYd")
		)
		(fp_rect
			(start -0.5842 1.3335)
			(end 0.5842 -1.3335)
			(stroke
				(width 0)
				(type default)
			)
			(fill no)
			(layer "F.Fab")
		)
		(pad "1" smd custom
			(at 0 -0.762 180)
			(size 0.2159 0.2159)
			(layers "F.Cu" "F.Mask" "F.Paste")
			(net "P5V_HDD2")
			(options
				(clearance outline)
				(anchor circle)
			)
			(primitives
				(gr_poly
					(pts
						(arc
							(start -0.3302 -0.4318)
							(mid -0.402042 -0.402042)
							(end -0.4318 -0.3302)
						)
						(arc
							(start -0.4318 0.3302)
							(mid -0.402042 0.402042)
							(end -0.3302 0.4318)
						)
						(arc
							(start 0.3302 0.4318)
							(mid 0.402042 0.402042)
							(end 0.4318 0.3302)
						)
						(arc
							(start 0.4318 -0.3302)
							(mid 0.402042 -0.402042)
							(end 0.3302 -0.4318)
						)
					)
					(width 0)
					(fill yes)
				)
			)
		)
		(pad "2" smd custom
			(at 0 0.762 180)
			(size 0.2159 0.2159)
			(layers "F.Cu" "F.Mask" "F.Paste")
			(net "GND")
			(options
				(clearance outline)
				(anchor circle)
			)
			(primitives
				(gr_poly
					(pts
						(arc
							(start -0.3302 -0.4318)
							(mid -0.402042 -0.402042)
							(end -0.4318 -0.3302)
						)
						(arc
							(start -0.4318 0.3302)
							(mid -0.402042 0.402042)
							(end -0.3302 0.4318)
						)
						(arc
							(start 0.3302 0.4318)
							(mid 0.402042 0.402042)
							(end 0.4318 0.3302)
						)
						(arc
							(start 0.4318 -0.3302)
							(mid 0.402042 -0.402042)
							(end 0.3302 -0.4318)
						)
					)
					(width 0)
					(fill yes)
				)
			)
		)
	)
	(footprint ""
		(layer "F.Cu")
		(at 50.927 -417.957 90)
		(property "Reference" "R248"
			(at 0 0 90)
			(layer "F.SilkS")
			(hide yes)
			(effects
				(font
					(size 1.27 1.27)
				)
			)
		)
		(property "Value" "4K7R2J-2-GP"
			(at 0.064008 -3.993896 90)
			(unlocked yes)
			(layer "F.Fab")
			(hide yes)
			(effects
				(font
					(size 1.016 1.016)
					(thickness 0.1524)
				)
			)
		)
		(property "Device Type" "R402H16"
			(at 0.064008 -5.517896 90)
			(unlocked yes)
			(layer "F.Fab")
			(hide yes)
			(effects
				(font
					(size 1.016 1.016)
					(thickness 0.1524)
				)
			)
		)
		(duplicate_pad_numbers_are_jumpers no)
		(fp_line
			(start 0.508 -0.9398)
			(end -0.508 -0.9398)
			(stroke
				(width 0.1524)
				(type default)
			)
			(layer "F.SilkS")
		)
		(fp_line
			(start -0.508 -0.9398)
			(end -0.508 0.9398)
			(stroke
				(width 0.1524)
				(type default)
			)
			(layer "F.SilkS")
		)
		(fp_rect
			(start -0.508 0.9398)
			(end 0.508 -0.9398)
			(stroke
				(width 0)
				(type default)
			)
			(fill no)
			(layer "F.CrtYd")
		)
		(fp_rect
			(start -0.508 0.9398)
			(end 0.508 -0.9398)
			(stroke
				(width 0)
				(type default)
			)
			(fill no)
			(layer "F.Fab")
		)
		(pad "1" smd custom
			(at 0 -0.4445 90)
			(size 0.1397 0.1397)
			(layers "F.Cu" "F.Mask" "F.Paste")
			(net "P12V")
			(options
				(clearance outline)
				(anchor circle)
			)
			(primitives
				(gr_poly
					(pts
						(arc
							(start -0.1778 -0.2794)
							(mid -0.249642 -0.249642)
							(end -0.2794 -0.1778)
						)
						(arc
							(start -0.2794 0.1778)
							(mid -0.249642 0.249642)
							(end -0.1778 0.2794)
						)
						(arc
							(start 0.1778 0.2794)
							(mid 0.249642 0.249642)
							(end 0.2794 0.1778)
						)
						(arc
							(start 0.2794 -0.1778)
							(mid 0.249642 -0.249642)
							(end 0.1778 -0.2794)
						)
					)
					(width 0)
					(fill yes)
				)
			)
		)
		(pad "2" smd custom
			(at 0 0.4445 90)
			(size 0.1397 0.1397)
			(layers "F.Cu" "F.Mask" "F.Paste")
			(net "SW_HDD10_R")
			(options
				(clearance outline)
				(anchor circle)
			)
			(primitives
				(gr_poly
					(pts
						(arc
							(start -0.1778 -0.2794)
							(mid -0.249642 -0.249642)
							(end -0.2794 -0.1778)
						)
						(arc
							(start -0.2794 0.1778)
							(mid -0.249642 0.249642)
							(end -0.1778 0.2794)
						)
						(arc
							(start 0.1778 0.2794)
							(mid 0.249642 0.249642)
							(end 0.2794 0.1778)
						)
						(arc
							(start 0.2794 -0.1778)
							(mid 0.249642 -0.249642)
							(end 0.1778 -0.2794)
						)
					)
					(width 0)
					(fill yes)
				)
			)
		)
	)
)
